# SCM (Grand Teton) — schematic netlist excerpt (pin names and nets, part order shuffled) for the footprints in the layout excerpt that follows; sources: Cadence DE-HDL packaged netlist, KiCad conversion of 12092022_DA0F0TMDCD0_F0T_Management_Board_D_brd_V3_OCP.brd

L23  Q_INDUCTOR4P_12  67/320MA EMPTY  pkg L_DLW21HNXA  page 29
  \1\  = USB_FPNL_DP
  \2\  = USB2_01_F_DP
  \3\  = USB2_01_F_DN
  \4\  = USB_FPNL_DN

C34  Q_CAP  0.1UF 25V 10% X7R  pkg 0402  page 22 : A = P3V3_AUX ; B = GND

(kicad_pcb
	(version 20260206)
	(generator "pcbnew")
	(generator_version "10.0")
	(general
		(thickness 1.6)
		(legacy_teardrops no)
	)
	(paper "A4")
	(title_block
		(title "12092022_DA0F0TMDCD0_F0T_Management_Board_D_brd_V3_OCP.brd")
		(comment 1 "Grand Teton / footprints 655-656 of 1440")
	)
	(layers
		(0 "F.Cu" signal "TOP")
		(4 "In1.Cu" signal "GND")
		(6 "In2.Cu" signal "IN1")
		(8 "In3.Cu" signal "GND1")
		(10 "In4.Cu" signal "IN2")
		(12 "In5.Cu" signal "VCC")
		(14 "In6.Cu" signal "VCC1")
		(16 "In7.Cu" signal "IN3")
		(18 "In8.Cu" signal "GND2")
		(20 "In9.Cu" signal "IN4")
		(22 "In10.Cu" signal "GND3")
		(2 "B.Cu" signal "BOTTOM")
		(9 "F.Adhes" user "F.Adhesive")
		(11 "B.Adhes" user "B.Adhesive")
		(13 "F.Paste" user "Package Geometry/Pastemask Top")
		(15 "B.Paste" user "Package Geometry/Pastemask Bottom")
		(5 "F.SilkS" user "Ref Des/Silkscreen Top")
		(7 "B.SilkS" user "Ref Des/Silkscreen Bottom")
		(1 "F.Mask" user "Board Geometry/Soldermask Top")
		(3 "B.Mask" user "Board Geometry/Soldermask Bottom")
		(17 "Dwgs.User" user "User.Drawings")
		(19 "Cmts.User" user "User.Comments")
		(21 "Eco1.User" user "User.Eco1")
		(23 "Eco2.User" user "User.Eco2")
		(25 "Edge.Cuts" user "Board Geometry/Outline")
		(27 "Margin" user)
		(31 "F.CrtYd" user "Package Geometry/Place Bound Top")
		(29 "B.CrtYd" user "Package Geometry/Place Bound Bottom")
		(35 "F.Fab" user "Ref Des/Assembly Top")
		(33 "B.Fab" user "Ref Des/Assembly Bottom")
	)
	(footprint ""
		(layer "F.Cu")
		(at 6.7818 -80.4926 180)
		(property "Reference" "C34"
			(at 0 0 180)
			(layer "F.SilkS")
			(hide yes)
			(effects
				(font
					(size 1.27 1.27)
				)
			)
		)
		(property "Value" ""
			(at 0 0 180)
			(layer "F.Fab")
			(effects
				(font
					(size 1.27 1.27)
				)
			)
		)
		(duplicate_pad_numbers_are_jumpers no)
		(fp_line
			(start 0.7874 0.4064)
			(end -0.7874 0.4064)
			(stroke
				(width 0.1524)
				(type default)
			)
			(layer "F.SilkS")
		)
		(fp_line
			(start 0.7874 -0.4064)
			(end 0.7874 0.4064)
			(stroke
				(width 0.1524)
				(type default)
			)
			(layer "F.SilkS")
		)
		(fp_line
			(start -0.7874 0.4064)
			(end -0.7874 -0.4064)
			(stroke
				(width 0.1524)
				(type default)
			)
			(layer "F.SilkS")
		)
		(fp_line
			(start -0.7874 -0.4064)
			(end 0.7874 -0.4064)
			(stroke
				(width 0.1524)
				(type default)
			)
			(layer "F.SilkS")
		)
		(fp_line
			(start 0.67945 0.3048)
			(end 0.120396 0.3048)
			(stroke
				(width 0.1)
				(type default)
			)
			(layer "F.Fab")
		)
		(fp_line
			(start 0.67945 -0.3048)
			(end 0.67945 0.3048)
			(stroke
				(width 0.1)
				(type default)
			)
			(layer "F.Fab")
		)
		(fp_line
			(start 0.12065 -0.2794)
			(end 0.12065 -0.3048)
			(stroke
				(width 0.1)
				(type default)
			)
			(layer "F.Fab")
		)
		(fp_line
			(start 0.12065 -0.3048)
			(end 0.67945 -0.3048)
			(stroke
				(width 0.1)
				(type default)
			)
			(layer "F.Fab")
		)
		(fp_line
			(start 0.120396 0.3048)
			(end 0.120396 0.2794)
			(stroke
				(width 0.1)
				(type default)
			)
			(layer "F.Fab")
		)
		(fp_line
			(start 0.120396 0.2794)
			(end -0.12065 0.2794)
			(stroke
				(width 0.1)
				(type default)
			)
			(layer "F.Fab")
		)
		(fp_line
			(start -0.12065 0.3048)
			(end -0.67945 0.3048)
			(stroke
				(width 0.1)
				(type default)
			)
			(layer "F.Fab")
		)
		(fp_line
			(start -0.12065 0.2794)
			(end -0.12065 0.3048)
			(stroke
				(width 0.1)
				(type default)
			)
			(layer "F.Fab")
		)
		(fp_line
			(start -0.12065 -0.2794)
			(end 0.12065 -0.2794)
			(stroke
				(width 0.1)
				(type default)
			)
			(layer "F.Fab")
		)
		(fp_line
			(start -0.12065 -0.305054)
			(end -0.12065 -0.2794)
			(stroke
				(width 0.1)
				(type default)
			)
			(layer "F.Fab")
		)
		(fp_line
			(start -0.67945 0.3048)
			(end -0.67945 -0.305054)
			(stroke
				(width 0.1)
				(type default)
			)
			(layer "F.Fab")
		)
		(fp_line
			(start -0.67945 -0.305054)
			(end -0.12065 -0.305054)
			(stroke
				(width 0.1)
				(type default)
			)
			(layer "F.Fab")
		)
		(pad "1" smd circle
			(at -0.40005 0 180)
			(size 0 0)
			(layers "F.Cu" "F.Mask" "F.Paste")
			(net "P3V3_AUX")
		)
		(pad "2" smd circle
			(at 0.40005 0 180)
			(size 0 0)
			(layers "F.Cu" "F.Mask" "F.Paste")
			(net "GND")
		)
	)
	(footprint ""
		(layer "F.Cu")
		(at 28.27401 -16.50365 90)
		(property "Reference" "L23"
			(at 0 0 90)
			(layer "F.SilkS")
			(hide yes)
			(effects
				(font
					(size 1.27 1.27)
				)
			)
		)
		(property "Value" ""
			(at 0 0 90)
			(layer "F.Fab")
			(effects
				(font
					(size 1.27 1.27)
				)
			)
		)
		(duplicate_pad_numbers_are_jumpers no)
		(fp_line
			(start 0.8636 -1.524)
			(end 0.8636 1.524)
			(stroke
				(width 0.1524)
				(type default)
			)
			(layer "F.SilkS")
		)
		(fp_line
			(start 0.38481 -1.524)
			(end 0.8636 -1.524)
			(stroke
				(width 0.1524)
				(type default)
			)
			(layer "F.SilkS")
		)
		(fp_line
			(start -0.8636 -1.524)
			(end -0.40767 -1.524)
			(stroke
				(width 0.1524)
				(type default)
			)
			(layer "F.SilkS")
		)
		(fp_line
			(start 0.8636 1.524)
			(end 0.49403 1.524)
			(stroke
				(width 0.1524)
				(type default)
			)
			(layer "F.SilkS")
		)
		(fp_line
			(start -0.45593 1.524)
			(end -0.8636 1.524)
			(stroke
				(width 0.1524)
				(type default)
			)
			(layer "F.SilkS")
		)
		(fp_line
			(start -0.8636 1.524)
			(end -0.8636 -1.524)
			(stroke
				(width 0.1524)
				(type default)
			)
			(layer "F.SilkS")
		)
		(fp_poly
			(pts
				(xy -1.1049 -1.06426) (xy -1.6129 -0.810514) (xy -1.6129 -1.31826)
			)
			(stroke
				(width 0)
				(type default)
			)
			(fill yes)
			(layer "F.SilkS")
		)
		(fp_line
			(start 0.700024 -1.100074)
			(end 0.700024 1.100074)
			(stroke
				(width 0.1)
				(type default)
			)
			(layer "F.Fab")
		)
		(fp_line
			(start -0.700024 -1.100074)
			(end 0.700024 -1.100074)
			(stroke
				(width 0.1)
				(type default)
			)
			(layer "F.Fab")
		)
		(fp_line
			(start 0.700024 1.100074)
			(end -0.700024 1.100074)
			(stroke
				(width 0.1)
				(type default)
			)
			(layer "F.Fab")
		)
		(fp_line
			(start -0.700024 1.100074)
			(end -0.700024 -1.100074)
			(stroke
				(width 0.1)
				(type default)
			)
			(layer "F.Fab")
		)
		(fp_poly
			(pts
				(xy -0.4572 -1.6256) (xy -0.7112 -2.1336) (xy -0.2032 -2.1336)
			)
			(stroke
				(width 0)
				(type default)
			)
			(fill yes)
			(layer "F.Fab")
		)
		(pad "1" smd rect
			(at -0.424942 -0.849884 90)
			(size 0.3556 0.9144)
			(layers "F.Cu" "F.Mask" "F.Paste")
			(net "USB_FPNL_DP")
		)
		(pad "2" smd rect
			(at -0.424942 0.849884 90)
			(size 0.3556 0.9144)
			(layers "F.Cu" "F.Mask" "F.Paste")
			(net "USB2_01_F_DP")
		)
		(pad "3" smd rect
			(at 0.424942 0.849884 90)
			(size 0.3556 0.9144)
			(layers "F.Cu" "F.Mask" "F.Paste")
			(net "USB2_01_F_DN")
		)
		(pad "4" smd rect
			(at 0.424942 -0.849884 90)
			(size 0.3556 0.9144)
			(layers "F.Cu" "F.Mask" "F.Paste")
			(net "USB_FPNL_DN")
		)
	)
)
